FILE_TYPE = CONNECTIVITY;
{Allegro Design Entry HDL 16.6-p007 (v16-6-112F) 10/10/2012}
"PAGE_NUMBER" = 143;
0"NC";
1"GND\g";
2"GND\g";
3"BMC_M_A4";
4"BMC_M_DQ9";
5"BMC_M_A0";
6"BMC_M_DQ4";
7"BMC_M_DQ7";
8"BMC_M_VREFCA";
9"BMC_M_A2";
10"BMC_M_A1";
11"BMC_M_A3";
12"BMC_M_A9";
13"BMC_M_A8";
14"BMC_M_A7";
15"BMC_M_A6";
16"BMC_M_A5";
17"TP_BMC_M_A15";
18"BMC_M_MACT_N";
19"BMC_M_A13";
20"BMC_M_A12";
21"BMC_M_DM1";
22"BMC_M_DM0";
23"BMC_M_DQS1_DN";
24"BMC_M_DQS1_DP";
25"BMC_M_DQ2";
26"BMC_M_DQ3";
27"BMC_M_DQ5";
28"BMC_M_DQ6";
29"BMC_M_DQS0_DN";
30"BMC_M_DQS0_DP";
31"BMC_M_DQ0";
32"BMC_M_DQ1";
33"BMC_M_DQ8";
34"BMC_M_DQ10";
35"BMC_M_DQ11";
36"BMC_M_DQ12";
37"BMC_M_DQ13";
38"BMC_M_DQ14";
39"BMC_M_DQ15";
40"BMC_M_BG0";
41"BMC_MIOZ";
42"BMC_M_BA0";
43"BMC_M_BA1";
44"BMC_M_ODT";
45"BMC_M_CKE";
46"BMC_M_CLK_DN";
47"BMC_M_CS_N";
48"BMC_M_CLK_DP";
49"BMC_M_RAS_N";
50"BMC_M_CAS_N";
51"BMC_M_WE_N";
52"BMC_M_A10";
53"BMC_M_A11";
%"GND"
"1","(-10250,-2150)","1","mstr_symbols","I57";
;
CDS_LIB"mstr_symbols"
SIZE"1B"
VOLTAGE"0.0V"
BODY_TYPE"PLUMBING"
HDL_POWER"GND";
"A\NAC"1;
%"RES"
"2","(-11000,-2150)","7","mstr_discrete","I58";
;
CDS_SEC"1"
CDS_LOCATION"R1T27"
LOCATION"R1T27"
VALUE"240"
TOLERANCE"1.0%"
MATERIAL"CHIP"
WATTAGE"1/16W"
PART_NUMBER"G21796-294"
PACK_TYPE"0402"
SEC_TYPE"0402"
SEC"1"
ROOM"BMC_MEMORY"
BOM_COST"SM_MEM"
CDS_LIB"mstr_discrete";
"A"
$PN"1"1;
"B"
$PN"2"41;
%"AST2520A1-GP-GP"
"1","(-12850,-1850)","0","w_hdl","I63";
;
CDS_SEC"1"
$SEC"1"
CDS_LOCATION"U25W4"
VALUE"AST2520A1-GP-GP"
LOCATION"U25W4"
CDS_LIB"w_hdl"
CDS_LMAN_SYM_OUTLINE"-575,1050,575,-1050"
PACK_TYPE"ASIC2-GB1"
PART_NUMBER"071.2520A.M001";
"MCS# \B"
$PN"AA12"47;
"MCKP"
$PN"AB11"48;
"MDQ8"
$PN"AA8"33;
"MDQ7"
$PN"V9"7;
"MRAS# \B"
$PN"W12"49;
"MWE# \B"
$PN"Y12"51;
"MDQ10"
$PN"Y7"34;
"MDQ11"
$PN"W8"35;
"MA14_MACT# \B"
$PN"Y15"18;
"MA13"
$PN"AB15"19;
"MDM0"
$PN"U8"22;
"MDQ12"
$PN"AA6"36;
"MDQ13"
$PN"W7"37;
"MDQ5"
$PN"Y9"27;
"MDQ6"
$PN"W9"28;
"MDQS0N"
$PN"AB10"29;
"MDQS0P"
$PN"AB9"30;
"MDQS1N"
$PN"AB6"23;
"MDQS1P"
$PN"AB7"24;
"MA0"
$PN"V13"5;
"MA1"
$PN"AB14"10;
"MA12"
$PN"Y14"20;
"MA2"
$PN"W14"9;
"MA3"
$PN"U14"11;
"MA4"
$PN"W15"3;
"MA5"
$PN"V15"16;
"MA6"
$PN"AB16"15;
"MA7"
$PN"AA16"14;
"MA8"
$PN"W16"13;
"MA9"
$PN"Y16"12;
"MBA0"
$PN"U12"42;
"MBA1"
$PN"Y13"43;
"MBA2_MBG0"
$PN"W13"40;
"MCKN"
$PN"AB12"46;
"MCKE"
$PN"Y11"45;
"MODT"
$PN"V11"44;
"MDQ9"
$PN"Y8"4;
"MVREF"
$PN"T9"8;
"MA11"
$PN"AA14"53;
"MA10"
$PN"U13"52;
"MCAS# \B"
$PN"AB13"50;
"MIOZ"
$PN"W11"41;
"MDM1"
$PN"AB8"21;
"MDQ14"
$PN"V7"38;
"MDQ15"
$PN"U7"39;
"MA15"
$PN"U15"17;
"MDQ0"
$PN"U10"31;
"MDQ1"
$PN"W10"32;
"MDQ2"
$PN"Y10"25;
"MDQ3"
$PN"AA10"26;
"MDQ4"
$PN"U9"6;
%"GND"
"1","(-10550,-2650)","2","mstr_symbols","I65";
;
VOLTAGE"0.0V"
SIZE"1B"
CDS_LIB"mstr_symbols"
BODY_TYPE"PLUMBING"
HDL_POWER"GND";
"A\NAC"2;
%"CAP_A"
"1","(-10550,-2450)","0","dev_discrete","I67";
;
PART_NUMBER"A36096-030"
PACK_TYPE"0402V"
MATERIAL"X7R"
LOCATION"C25W22"
VALUE"0.1UF"
VOLTAGE"16V"
TOLERANCE"10%"
CDS_LIB"dev_discrete"
CDS_SEC"1"
ROOM"VDDQ_KLM_PWR_VR"
SEC_TYPE"0402V"
SEC"1"
CDS_LOCATION"C25W22";
"B"
$PN"2"2;
"A"
$PN"1"8;
END.
